# S9S_MB_2U (Grand Teton) — schematic netlist excerpt (pin names and nets, part order shuffled) for the footprints in the layout excerpt that follows; sources: Cadence DE-HDL packaged netlist, KiCad conversion of 03242023_DA0F0TMBIJ0_F0T_Motherboard_J_brd_V01_OCP.brd

R2393  Q_RES  1K 1% CHIP  pkg 0402LF  page 274 : A = P3V3_AUX ; B = PVCCINFAON_CPU0_PIN_ALERT
R31  Q_RES  84.5K 1% CHIP  pkg 0402LF  page 87 : A = PD_CHC_CPU0_DIMM2_SAA ; B = GND

(kicad_pcb
	(version 20260206)
	(generator "pcbnew")
	(generator_version "10.0")
	(general
		(thickness 1.6)
		(legacy_teardrops no)
	)
	(paper "A4")
	(title_block
		(title "03242023_DA0F0TMBIJ0_F0T_Motherboard_J_brd_V01_OCP.brd")
		(comment 1 "Grand Teton / footprints 5590-5591 of 6105")
	)
	(layers
		(0 "F.Cu" signal "TOP")
		(4 "In1.Cu" signal "GND")
		(6 "In2.Cu" signal "IN1")
		(8 "In3.Cu" signal "GND1")
		(10 "In4.Cu" signal "IN2")
		(12 "In5.Cu" signal "GND2")
		(14 "In6.Cu" signal "IN3")
		(16 "In7.Cu" signal "GND3")
		(18 "In8.Cu" signal "VCC")
		(20 "In9.Cu" signal "VCC1")
		(22 "In10.Cu" signal "GND4")
		(24 "In11.Cu" signal "IN4")
		(26 "In12.Cu" signal "GND5")
		(28 "In13.Cu" signal "IN5")
		(30 "In14.Cu" signal "GND6")
		(32 "In15.Cu" signal "IN6")
		(34 "In16.Cu" signal "GND7")
		(2 "B.Cu" signal "BOTTOM")
		(9 "F.Adhes" user "F.Adhesive")
		(11 "B.Adhes" user "B.Adhesive")
		(13 "F.Paste" user "Package Geometry/Pastemask Top")
		(15 "B.Paste" user "Package Geometry/Pastemask Bottom")
		(5 "F.SilkS" user "Ref Des/Silkscreen Top")
		(7 "B.SilkS" user "Ref Des/Silkscreen Bottom")
		(1 "F.Mask" user "Board Geometry/Soldermask Top")
		(3 "B.Mask" user "Board Geometry/Soldermask Bottom")
		(17 "Dwgs.User" user "User.Drawings")
		(19 "Cmts.User" user "User.Comments")
		(21 "Eco1.User" user "User.Eco1")
		(23 "Eco2.User" user "User.Eco2")
		(25 "Edge.Cuts" user "Board Geometry/Outline")
		(27 "Margin" user)
		(31 "F.CrtYd" user "Package Geometry/Place Bound Top")
		(29 "B.CrtYd" user "Package Geometry/Place Bound Bottom")
		(35 "F.Fab" user "Ref Des/Assembly Top")
		(33 "B.Fab" user "Ref Des/Assembly Bottom")
	)
	(footprint ""
		(layer "B.Cu")
		(at 430.600104 -135.510778)
		(property "Reference" "R2393"
			(at 0 0 0)
			(layer "B.SilkS")
			(hide yes)
			(effects
				(font
					(size 1.27 1.27)
				)
				(justify mirror)
			)
		)
		(property "Value" ""
			(at 0 0 0)
			(layer "B.Fab")
			(effects
				(font
					(size 1.27 1.27)
				)
				(justify mirror)
			)
		)
		(duplicate_pad_numbers_are_jumpers no)
		(fp_line
			(start -0.7874 -0.4064)
			(end -0.7874 0.4064)
			(stroke
				(width 0.1524)
				(type default)
			)
			(layer "B.SilkS")
		)
		(fp_line
			(start -0.7874 0.4064)
			(end 0.7874 0.4064)
			(stroke
				(width 0.1524)
				(type default)
			)
			(layer "B.SilkS")
		)
		(fp_line
			(start 0.7874 -0.4064)
			(end -0.7874 -0.4064)
			(stroke
				(width 0.1524)
				(type default)
			)
			(layer "B.SilkS")
		)
		(fp_line
			(start 0.7874 0.4064)
			(end 0.7874 -0.4064)
			(stroke
				(width 0.1524)
				(type default)
			)
			(layer "B.SilkS")
		)
		(fp_line
			(start -0.67945 -0.3048)
			(end -0.67945 0.3048)
			(stroke
				(width 0.1)
				(type default)
			)
			(layer "B.Fab")
		)
		(fp_line
			(start -0.67945 0.3048)
			(end -0.120396 0.3048)
			(stroke
				(width 0.1)
				(type default)
			)
			(layer "B.Fab")
		)
		(fp_line
			(start -0.12065 -0.3048)
			(end -0.67945 -0.3048)
			(stroke
				(width 0.1)
				(type default)
			)
			(layer "B.Fab")
		)
		(fp_line
			(start -0.12065 -0.2794)
			(end -0.12065 -0.3048)
			(stroke
				(width 0.1)
				(type default)
			)
			(layer "B.Fab")
		)
		(fp_line
			(start -0.120396 0.2794)
			(end 0.12065 0.2794)
			(stroke
				(width 0.1)
				(type default)
			)
			(layer "B.Fab")
		)
		(fp_line
			(start -0.120396 0.3048)
			(end -0.120396 0.2794)
			(stroke
				(width 0.1)
				(type default)
			)
			(layer "B.Fab")
		)
		(fp_line
			(start 0.12065 -0.305054)
			(end 0.12065 -0.2794)
			(stroke
				(width 0.1)
				(type default)
			)
			(layer "B.Fab")
		)
		(fp_line
			(start 0.12065 -0.2794)
			(end -0.12065 -0.2794)
			(stroke
				(width 0.1)
				(type default)
			)
			(layer "B.Fab")
		)
		(fp_line
			(start 0.12065 0.2794)
			(end 0.12065 0.3048)
			(stroke
				(width 0.1)
				(type default)
			)
			(layer "B.Fab")
		)
		(fp_line
			(start 0.12065 0.3048)
			(end 0.67945 0.3048)
			(stroke
				(width 0.1)
				(type default)
			)
			(layer "B.Fab")
		)
		(fp_line
			(start 0.67945 -0.305054)
			(end 0.12065 -0.305054)
			(stroke
				(width 0.1)
				(type default)
			)
			(layer "B.Fab")
		)
		(fp_line
			(start 0.67945 0.3048)
			(end 0.67945 -0.305054)
			(stroke
				(width 0.1)
				(type default)
			)
			(layer "B.Fab")
		)
		(pad "1" smd circle
			(at 0.40005 0 180)
			(size 0 0)
			(layers "B.Cu" "B.Mask" "B.Paste")
			(net "P3V3_AUX")
		)
		(pad "2" smd circle
			(at -0.40005 0 180)
			(size 0 0)
			(layers "B.Cu" "B.Mask" "B.Paste")
			(net "PVCCINFAON_CPU0_PIN_ALERT")
		)
	)
	(footprint ""
		(layer "B.Cu")
		(at 280.852118 -319.120774 -90)
		(property "Reference" "R31"
			(at 0 0 90)
			(layer "B.SilkS")
			(hide yes)
			(effects
				(font
					(size 1.27 1.27)
				)
				(justify mirror)
			)
		)
		(property "Value" ""
			(at 0 0 90)
			(layer "B.Fab")
			(effects
				(font
					(size 1.27 1.27)
				)
				(justify mirror)
			)
		)
		(duplicate_pad_numbers_are_jumpers no)
		(fp_line
			(start -0.7874 0.4064)
			(end 0.7874 0.4064)
			(stroke
				(width 0.1524)
				(type default)
			)
			(layer "B.SilkS")
		)
		(fp_line
			(start 0.7874 0.4064)
			(end 0.7874 -0.4064)
			(stroke
				(width 0.1524)
				(type default)
			)
			(layer "B.SilkS")
		)
		(fp_line
			(start -0.7874 -0.4064)
			(end -0.7874 0.4064)
			(stroke
				(width 0.1524)
				(type default)
			)
			(layer "B.SilkS")
		)
		(fp_line
			(start 0.7874 -0.4064)
			(end -0.7874 -0.4064)
			(stroke
				(width 0.1524)
				(type default)
			)
			(layer "B.SilkS")
		)
		(fp_line
			(start -0.67945 0.3048)
			(end -0.120396 0.3048)
			(stroke
				(width 0.1)
				(type default)
			)
			(layer "B.Fab")
		)
		(fp_line
			(start -0.120396 0.3048)
			(end -0.120396 0.2794)
			(stroke
				(width 0.1)
				(type default)
			)
			(layer "B.Fab")
		)
		(fp_line
			(start 0.12065 0.3048)
			(end 0.67945 0.3048)
			(stroke
				(width 0.1)
				(type default)
			)
			(layer "B.Fab")
		)
		(fp_line
			(start 0.67945 0.3048)
			(end 0.67945 -0.305054)
			(stroke
				(width 0.1)
				(type default)
			)
			(layer "B.Fab")
		)
		(fp_line
			(start -0.120396 0.2794)
			(end 0.12065 0.2794)
			(stroke
				(width 0.1)
				(type default)
			)
			(layer "B.Fab")
		)
		(fp_line
			(start 0.12065 0.2794)
			(end 0.12065 0.3048)
			(stroke
				(width 0.1)
				(type default)
			)
			(layer "B.Fab")
		)
		(fp_line
			(start -0.12065 -0.2794)
			(end -0.12065 -0.3048)
			(stroke
				(width 0.1)
				(type default)
			)
			(layer "B.Fab")
		)
		(fp_line
			(start 0.12065 -0.2794)
			(end -0.12065 -0.2794)
			(stroke
				(width 0.1)
				(type default)
			)
			(layer "B.Fab")
		)
		(fp_line
			(start -0.67945 -0.3048)
			(end -0.67945 0.3048)
			(stroke
				(width 0.1)
				(type default)
			)
			(layer "B.Fab")
		)
		(fp_line
			(start -0.12065 -0.3048)
			(end -0.67945 -0.3048)
			(stroke
				(width 0.1)
				(type default)
			)
			(layer "B.Fab")
		)
		(fp_line
			(start 0.12065 -0.305054)
			(end 0.12065 -0.2794)
			(stroke
				(width 0.1)
				(type default)
			)
			(layer "B.Fab")
		)
		(fp_line
			(start 0.67945 -0.305054)
			(end 0.12065 -0.305054)
			(stroke
				(width 0.1)
				(type default)
			)
			(layer "B.Fab")
		)
		(pad "1" smd circle
			(at 0.40005 0 90)
			(size 0 0)
			(layers "B.Cu" "B.Mask" "B.Paste")
			(net "PD_CHC_CPU0_DIMM2_SAA")
		)
		(pad "2" smd circle
			(at -0.40005 0 90)
			(size 0 0)
			(layers "B.Cu" "B.Mask" "B.Paste")
			(net "GND")
		)
	)
)
